# T6G (Grand Teton) — schematic netlist excerpt (pin names and nets, part order shuffled) for the footprints in the layout excerpt that follows; sources: Cadence DE-HDL packaged netlist, KiCad conversion of 04192023_DAF0TMB3IC0_F0TG_MB_C_brd_V02_OCP.brd

C212  Q_CAP  0.001UF 50V 10% EMPTY  pkg C0402  page 27 : A = JTAG_CPU0_DBREQ_N ; B = GND
R4640  Q_RES  243 1% CHIP  pkg 1206LF  page 188 : A = P5V ; B = VR_P5V_EN_D
PC352_3  Q_CAP  22UF 16V 20% X6S  pkg C0805  page 216 : A = SW_P12V_AUX_PVDDCR_SOC_P1_FLT ; B = GND

(kicad_pcb
	(version 20260206)
	(generator "pcbnew")
	(generator_version "10.0")
	(general
		(thickness 1.6)
		(legacy_teardrops no)
	)
	(paper "A4")
	(title_block
		(title "04192023_DAF0TMB3IC0_F0TG_MB_C_brd_V02_OCP.brd")
		(comment 1 "Grand Teton / footprints 6527-6529 of 8354")
	)
	(layers
		(0 "F.Cu" signal "TOP")
		(4 "In1.Cu" signal "GND")
		(6 "In2.Cu" signal "IN1")
		(8 "In3.Cu" signal "GND1")
		(10 "In4.Cu" signal "IN2")
		(12 "In5.Cu" signal "GND2")
		(14 "In6.Cu" signal "IN3")
		(16 "In7.Cu" signal "GND3")
		(18 "In8.Cu" signal "VCC")
		(20 "In9.Cu" signal "VCC1")
		(22 "In10.Cu" signal "GND4")
		(24 "In11.Cu" signal "IN4")
		(26 "In12.Cu" signal "GND5")
		(28 "In13.Cu" signal "IN5")
		(30 "In14.Cu" signal "GND6")
		(32 "In15.Cu" signal "IN6")
		(34 "In16.Cu" signal "GND7")
		(2 "B.Cu" signal "BOTTOM")
		(9 "F.Adhes" user "F.Adhesive")
		(11 "B.Adhes" user "B.Adhesive")
		(13 "F.Paste" user "Package Geometry/Pastemask Top")
		(15 "B.Paste" user "Package Geometry/Pastemask Bottom")
		(5 "F.SilkS" user "Ref Des/Silkscreen Top")
		(7 "B.SilkS" user "Ref Des/Silkscreen Bottom")
		(1 "F.Mask" user "Board Geometry/Soldermask Top")
		(3 "B.Mask" user "Board Geometry/Soldermask Bottom")
		(17 "Dwgs.User" user "User.Drawings")
		(19 "Cmts.User" user "User.Comments")
		(21 "Eco1.User" user "User.Eco1")
		(23 "Eco2.User" user "User.Eco2")
		(25 "Edge.Cuts" user "Board Geometry/Outline")
		(27 "Margin" user)
		(31 "F.CrtYd" user "Package Geometry/Place Bound Top")
		(29 "B.CrtYd" user "Package Geometry/Place Bound Bottom")
		(35 "F.Fab" user "Ref Des/Assembly Top")
		(33 "B.Fab" user "Ref Des/Assembly Bottom")
	)
	(footprint ""
		(layer "B.Cu")
		(at 400.358102 -152.29078 -90)
		(property "Reference" "R4640"
			(at 0 0 90)
			(layer "B.SilkS")
			(hide yes)
			(effects
				(font
					(size 1.27 1.27)
				)
				(justify mirror)
			)
		)
		(property "Value" ""
			(at 0 0 90)
			(layer "B.Fab")
			(effects
				(font
					(size 1.27 1.27)
				)
				(justify mirror)
			)
		)
		(duplicate_pad_numbers_are_jumpers no)
		(fp_line
			(start -2.234946 0.9271)
			(end 2.234946 0.9271)
			(stroke
				(width 0.1524)
				(type default)
			)
			(layer "B.SilkS")
		)
		(fp_line
			(start 2.234946 0.9271)
			(end 2.234946 -0.9271)
			(stroke
				(width 0.1524)
				(type default)
			)
			(layer "B.SilkS")
		)
		(fp_line
			(start -2.234946 -0.9271)
			(end -2.234946 0.9271)
			(stroke
				(width 0.1524)
				(type default)
			)
			(layer "B.SilkS")
		)
		(fp_line
			(start 2.234946 -0.9271)
			(end -2.234946 -0.9271)
			(stroke
				(width 0.1524)
				(type default)
			)
			(layer "B.SilkS")
		)
		(fp_line
			(start -1.575054 0.824992)
			(end -1.575054 -0.824992)
			(stroke
				(width 0.1)
				(type default)
			)
			(layer "B.Fab")
		)
		(fp_line
			(start 1.575054 0.824992)
			(end -1.575054 0.824992)
			(stroke
				(width 0.1)
				(type default)
			)
			(layer "B.Fab")
		)
		(fp_line
			(start -1.575054 -0.824992)
			(end 1.575054 -0.824992)
			(stroke
				(width 0.1)
				(type default)
			)
			(layer "B.Fab")
		)
		(fp_line
			(start 1.575054 -0.824992)
			(end 1.575054 0.824992)
			(stroke
				(width 0.1)
				(type default)
			)
			(layer "B.Fab")
		)
		(pad "1" smd rect
			(at 1.599946 0 90)
			(size 1.016 1.6002)
			(layers "B.Cu" "B.Mask" "B.Paste")
			(net "P5V")
		)
		(pad "2" smd rect
			(at -1.599946 0 90)
			(size 1.016 1.6002)
			(layers "B.Cu" "B.Mask" "B.Paste")
			(net "VR_P5V_EN_D")
		)
	)
	(footprint ""
		(layer "B.Cu")
		(at 378.250958 -205.101952 90)
		(property "Reference" "C212"
			(at 0 0 90)
			(layer "B.SilkS")
			(hide yes)
			(effects
				(font
					(size 1.27 1.27)
				)
				(justify mirror)
			)
		)
		(property "Value" ""
			(at 0 0 90)
			(layer "B.Fab")
			(effects
				(font
					(size 1.27 1.27)
				)
				(justify mirror)
			)
		)
		(duplicate_pad_numbers_are_jumpers no)
		(fp_line
			(start 0.7874 -0.4064)
			(end -0.7874 -0.4064)
			(stroke
				(width 0.1524)
				(type default)
			)
			(layer "B.SilkS")
		)
		(fp_line
			(start -0.7874 -0.4064)
			(end -0.7874 0.4064)
			(stroke
				(width 0.1524)
				(type default)
			)
			(layer "B.SilkS")
		)
		(fp_line
			(start 0.7874 0.4064)
			(end 0.7874 -0.4064)
			(stroke
				(width 0.1524)
				(type default)
			)
			(layer "B.SilkS")
		)
		(fp_line
			(start -0.7874 0.4064)
			(end 0.7874 0.4064)
			(stroke
				(width 0.1524)
				(type default)
			)
			(layer "B.SilkS")
		)
		(fp_line
			(start 0.67945 -0.305054)
			(end 0.12065 -0.305054)
			(stroke
				(width 0.1)
				(type default)
			)
			(layer "B.Fab")
		)
		(fp_line
			(start 0.12065 -0.305054)
			(end 0.12065 -0.2794)
			(stroke
				(width 0.1)
				(type default)
			)
			(layer "B.Fab")
		)
		(fp_line
			(start -0.12065 -0.3048)
			(end -0.67945 -0.3048)
			(stroke
				(width 0.1)
				(type default)
			)
			(layer "B.Fab")
		)
		(fp_line
			(start -0.67945 -0.3048)
			(end -0.67945 0.3048)
			(stroke
				(width 0.1)
				(type default)
			)
			(layer "B.Fab")
		)
		(fp_line
			(start 0.12065 -0.2794)
			(end -0.12065 -0.2794)
			(stroke
				(width 0.1)
				(type default)
			)
			(layer "B.Fab")
		)
		(fp_line
			(start -0.12065 -0.2794)
			(end -0.12065 -0.3048)
			(stroke
				(width 0.1)
				(type default)
			)
			(layer "B.Fab")
		)
		(fp_line
			(start 0.12065 0.2794)
			(end 0.12065 0.3048)
			(stroke
				(width 0.1)
				(type default)
			)
			(layer "B.Fab")
		)
		(fp_line
			(start -0.120396 0.2794)
			(end 0.12065 0.2794)
			(stroke
				(width 0.1)
				(type default)
			)
			(layer "B.Fab")
		)
		(fp_line
			(start 0.67945 0.3048)
			(end 0.67945 -0.305054)
			(stroke
				(width 0.1)
				(type default)
			)
			(layer "B.Fab")
		)
		(fp_line
			(start 0.12065 0.3048)
			(end 0.67945 0.3048)
			(stroke
				(width 0.1)
				(type default)
			)
			(layer "B.Fab")
		)
		(fp_line
			(start -0.120396 0.3048)
			(end -0.120396 0.2794)
			(stroke
				(width 0.1)
				(type default)
			)
			(layer "B.Fab")
		)
		(fp_line
			(start -0.67945 0.3048)
			(end -0.120396 0.3048)
			(stroke
				(width 0.1)
				(type default)
			)
			(layer "B.Fab")
		)
		(pad "1" smd circle
			(at 0.40005 0 270)
			(size 0 0)
			(layers "B.Cu" "B.Mask" "B.Paste")
			(net "JTAG_CPU0_DBREQ_N")
		)
		(pad "2" smd circle
			(at -0.40005 0 270)
			(size 0 0)
			(layers "B.Cu" "B.Mask" "B.Paste")
			(net "GND")
		)
	)
	(footprint ""
		(layer "B.Cu")
		(at 131.153154 -152.724612 90)
		(property "Reference" "PC352_3"
			(at 0 0 90)
			(layer "B.SilkS")
			(hide yes)
			(effects
				(font
					(size 1.27 1.27)
				)
				(justify mirror)
			)
		)
		(property "Value" ""
			(at 0 0 90)
			(layer "B.Fab")
			(effects
				(font
					(size 1.27 1.27)
				)
				(justify mirror)
			)
		)
		(duplicate_pad_numbers_are_jumpers no)
		(fp_line
			(start 1.524 -0.762)
			(end -1.524 -0.762)
			(stroke
				(width 0.1524)
				(type default)
			)
			(layer "B.SilkS")
		)
		(fp_line
			(start -1.524 -0.762)
			(end -1.524 0.762)
			(stroke
				(width 0.1524)
				(type default)
			)
			(layer "B.SilkS")
		)
		(fp_line
			(start 1.524 0.762)
			(end 1.524 -0.762)
			(stroke
				(width 0.1524)
				(type default)
			)
			(layer "B.SilkS")
		)
		(fp_line
			(start -1.524 0.762)
			(end 1.524 0.762)
			(stroke
				(width 0.1524)
				(type default)
			)
			(layer "B.SilkS")
		)
		(fp_line
			(start 1.1049 -0.724916)
			(end 1.1049 0.724916)
			(stroke
				(width 0.1)
				(type default)
			)
			(layer "B.Fab")
		)
		(fp_line
			(start -1.1049 -0.724916)
			(end 1.1049 -0.724916)
			(stroke
				(width 0.1)
				(type default)
			)
			(layer "B.Fab")
		)
		(fp_line
			(start 1.1049 0.724916)
			(end -1.1049 0.724916)
			(stroke
				(width 0.1)
				(type default)
			)
			(layer "B.Fab")
		)
		(fp_line
			(start -1.1049 0.724916)
			(end -1.1049 -0.724916)
			(stroke
				(width 0.1)
				(type default)
			)
			(layer "B.Fab")
		)
		(pad "1" smd rect
			(at 0.889 0 90)
			(size 1.016 1.27)
			(layers "B.Cu" "B.Mask" "B.Paste")
			(net "SW_P12V_AUX_PVDDCR_SOC_P1_FLT")
		)
		(pad "2" smd rect
			(at -0.889 0 90)
			(size 1.016 1.27)
			(layers "B.Cu" "B.Mask" "B.Paste")
			(net "GND")
		)
	)
)
